(kicad_pcb
	(version 20260206)
	(generator "pcbnew")
	(generator_version "10.0")
	(general
		(thickness 1.6)
		(legacy_teardrops no)
	)
	(paper "A4")
	(title_block
		(title "Bryce Canyon_SCC_16316-1_OCP.brd")
		(comment 1 "Bryce Canyon / footprints 1229-1235 of 1561")
	)
	(layers
		(0 "F.Cu" signal "TOP")
		(4 "In1.Cu" signal "L2GND")
		(6 "In2.Cu" signal "L3")
		(8 "In3.Cu" signal "L4VCC")
		(10 "In4.Cu" signal "L5VCC")
		(12 "In5.Cu" signal "L6")
		(14 "In6.Cu" signal "L7GND")
		(2 "B.Cu" signal "BOTTOM")
		(9 "F.Adhes" user "F.Adhesive")
		(11 "B.Adhes" user "B.Adhesive")
		(13 "F.Paste" user "Package Geometry/Pastemask Top")
		(15 "B.Paste" user "Package Geometry/Pastemask Bottom")
		(5 "F.SilkS" user "Ref Des/Silkscreen Top")
		(7 "B.SilkS" user "Ref Des/Silkscreen Bottom")
		(1 "F.Mask" user "Board Geometry/Soldermask Top")
		(3 "B.Mask" user "Board Geometry/Soldermask Bottom")
		(17 "Dwgs.User" user "User.Drawings")
		(19 "Cmts.User" user "User.Comments")
		(21 "Eco1.User" user "User.Eco1")
		(23 "Eco2.User" user "User.Eco2")
		(25 "Edge.Cuts" user "Board Geometry/Outline")
		(27 "Margin" user)
		(31 "F.CrtYd" user "Package Geometry/Place Bound Top")
		(29 "B.CrtYd" user "Package Geometry/Place Bound Bottom")
		(35 "F.Fab" user "Ref Des/Assembly Top")
		(33 "B.Fab" user "Ref Des/Assembly Bottom")
	)
	(footprint ""
		(layer "B.Cu")
		(at 128.524 -89.7382)
		(property "Reference" "R64"
			(at 0 0 0)
			(layer "B.SilkS")
			(hide yes)
			(effects
				(font
					(size 1.27 1.27)
				)
				(justify mirror)
			)
		)
		(property "Value" "4K7R2F-GP"
			(at -0.064008 -3.993896 0)
			(unlocked yes)
			(layer "B.Fab")
			(hide yes)
			(effects
				(font
					(size 1.016 1.016)
					(thickness 0.1524)
				)
				(justify mirror)
			)
		)
		(property "Device Type" "R402H16"
			(at -0.064008 -5.517896 0)
			(unlocked yes)
			(layer "B.Fab")
			(hide yes)
			(effects
				(font
					(size 1.016 1.016)
					(thickness 0.1524)
				)
				(justify mirror)
			)
		)
		(duplicate_pad_numbers_are_jumpers no)
		(fp_line
			(start -0.508 -0.9398)
			(end 0.508 -0.9398)
			(stroke
				(width 0.1524)
				(type default)
			)
			(layer "B.SilkS")
		)
		(fp_line
			(start 0.508 -0.9398)
			(end 0.508 0.9398)
			(stroke
				(width 0.1524)
				(type default)
			)
			(layer "B.SilkS")
		)
		(fp_rect
			(start 0.508 0.9398)
			(end -0.508 -0.9398)
			(stroke
				(width 0)
				(type default)
			)
			(fill no)
			(layer "B.CrtYd")
		)
		(fp_rect
			(start 0.508 0.9398)
			(end -0.508 -0.9398)
			(stroke
				(width 0)
				(type default)
			)
			(fill no)
			(layer "B.Fab")
		)
		(pad "1" smd custom
			(at 0 -0.4445 180)
			(size 0.1397 0.1397)
			(layers "B.Cu" "B.Mask" "B.Paste")
			(net "P1V8_E")
			(options
				(clearance outline)
				(anchor circle)
			)
			(primitives
				(gr_poly
					(pts
						(arc
							(start -0.1778 0.2794)
							(mid -0.249642 0.249642)
							(end -0.2794 0.1778)
						)
						(arc
							(start -0.2794 -0.1778)
							(mid -0.249642 -0.249642)
							(end -0.1778 -0.2794)
						)
						(arc
							(start 0.1778 -0.2794)
							(mid 0.249642 -0.249642)
							(end 0.2794 -0.1778)
						)
						(arc
							(start 0.2794 0.1778)
							(mid 0.249642 0.249642)
							(end 0.1778 0.2794)
						)
					)
					(width 0)
					(fill yes)
				)
			)
		)
		(pad "2" smd custom
			(at 0 0.4445 180)
			(size 0.1397 0.1397)
			(layers "B.Cu" "B.Mask" "B.Paste")
			(net "I2C_CLIP_SCL7_LS")
			(options
				(clearance outline)
				(anchor circle)
			)
			(primitives
				(gr_poly
					(pts
						(arc
							(start -0.1778 0.2794)
							(mid -0.249642 0.249642)
							(end -0.2794 0.1778)
						)
						(arc
							(start -0.2794 -0.1778)
							(mid -0.249642 -0.249642)
							(end -0.1778 -0.2794)
						)
						(arc
							(start 0.1778 -0.2794)
							(mid 0.249642 -0.249642)
							(end 0.2794 -0.1778)
						)
						(arc
							(start 0.2794 0.1778)
							(mid 0.249642 0.249642)
							(end 0.1778 0.2794)
						)
					)
					(width 0)
					(fill yes)
				)
			)
		)
	)
	(footprint ""
		(layer "B.Cu")
		(at 184.465468 -44.78401 90)
		(property "Reference" "C461"
			(at 0 0 90)
			(layer "B.SilkS")
			(hide yes)
			(effects
				(font
					(size 1.27 1.27)
				)
				(justify mirror)
			)
		)
		(property "Value" "SCD1U6D3V1KX-GP"
			(at 2.8321 -1.7399 90)
			(unlocked yes)
			(layer "B.Fab")
			(hide yes)
			(effects
				(font
					(size 1.016 1.016)
					(thickness 0.1524)
				)
				(justify mirror)
			)
		)
		(property "Device Type" "C0201H13"
			(at 2.8321 -3.2639 90)
			(unlocked yes)
			(layer "B.Fab")
			(hide yes)
			(effects
				(font
					(size 1.016 1.016)
					(thickness 0.1524)
				)
				(justify mirror)
			)
		)
		(duplicate_pad_numbers_are_jumpers no)
		(fp_rect
			(start 0.2794 0.6477)
			(end -0.2794 -0.6477)
			(stroke
				(width 0)
				(type default)
			)
			(fill no)
			(layer "B.CrtYd")
		)
		(fp_rect
			(start 0.2794 0.6477)
			(end -0.2794 -0.6477)
			(stroke
				(width 0)
				(type default)
			)
			(fill no)
			(layer "B.Fab")
		)
		(pad "1" smd custom
			(at 0 -0.2794 270)
			(size 0.0762 0.0762)
			(layers "B.Cu" "B.Mask" "B.Paste")
			(net "P1V8_C")
			(options
				(clearance outline)
				(anchor circle)
			)
			(primitives
				(gr_poly
					(pts
						(arc
							(start 0.1524 0.127)
							(mid 0.137521 0.162921)
							(end 0.1016 0.1778)
						)
						(arc
							(start -0.1016 0.1778)
							(mid -0.137521 0.162921)
							(end -0.1524 0.127)
						)
						(arc
							(start -0.1524 -0.127)
							(mid -0.137521 -0.162921)
							(end -0.1016 -0.1778)
						)
						(arc
							(start 0.1016 -0.1778)
							(mid 0.137521 -0.162921)
							(end 0.1524 -0.127)
						)
					)
					(width 0)
					(fill yes)
				)
			)
		)
		(pad "2" smd custom
			(at 0 0.2794 270)
			(size 0.0762 0.0762)
			(layers "B.Cu" "B.Mask" "B.Paste")
			(net "GND")
			(options
				(clearance outline)
				(anchor circle)
			)
			(primitives
				(gr_poly
					(pts
						(arc
							(start 0.1524 0.127)
							(mid 0.137521 0.162921)
							(end 0.1016 0.1778)
						)
						(arc
							(start -0.1016 0.1778)
							(mid -0.137521 0.162921)
							(end -0.1524 0.127)
						)
						(arc
							(start -0.1524 -0.127)
							(mid -0.137521 -0.162921)
							(end -0.1016 -0.1778)
						)
						(arc
							(start 0.1016 -0.1778)
							(mid 0.137521 -0.162921)
							(end 0.1524 -0.127)
						)
					)
					(width 0)
					(fill yes)
				)
			)
		)
	)
	(footprint ""
		(layer "B.Cu")
		(at 192.73901 -35.669982 -90)
		(property "Reference" "R187"
			(at 0 0 90)
			(layer "B.SilkS")
			(hide yes)
			(effects
				(font
					(size 1.27 1.27)
				)
				(justify mirror)
			)
		)
		(property "Value" "2K2R2F-GP"
			(at -0.064008 -3.993896 270)
			(unlocked yes)
			(layer "B.Fab")
			(hide yes)
			(effects
				(font
					(size 1.016 1.016)
					(thickness 0.1524)
				)
				(justify mirror)
			)
		)
		(property "Device Type" "R402H16"
			(at -0.064008 -5.517896 270)
			(unlocked yes)
			(layer "B.Fab")
			(hide yes)
			(effects
				(font
					(size 1.016 1.016)
					(thickness 0.1524)
				)
				(justify mirror)
			)
		)
		(duplicate_pad_numbers_are_jumpers no)
		(fp_line
			(start -0.508 -0.9398)
			(end 0.508 -0.9398)
			(stroke
				(width 0.1524)
				(type default)
			)
			(layer "B.SilkS")
		)
		(fp_line
			(start 0.508 -0.9398)
			(end 0.508 0.9398)
			(stroke
				(width 0.1524)
				(type default)
			)
			(layer "B.SilkS")
		)
		(fp_rect
			(start 0.508 0.9398)
			(end -0.508 -0.9398)
			(stroke
				(width 0)
				(type default)
			)
			(fill no)
			(layer "B.CrtYd")
		)
		(fp_rect
			(start 0.508 0.9398)
			(end -0.508 -0.9398)
			(stroke
				(width 0)
				(type default)
			)
			(fill no)
			(layer "B.Fab")
		)
		(pad "1" smd custom
			(at 0 -0.4445 90)
			(size 0.1397 0.1397)
			(layers "B.Cu" "B.Mask" "B.Paste")
			(net "P1V8_C")
			(options
				(clearance outline)
				(anchor circle)
			)
			(primitives
				(gr_poly
					(pts
						(arc
							(start -0.1778 0.2794)
							(mid -0.249642 0.249642)
							(end -0.2794 0.1778)
						)
						(arc
							(start -0.2794 -0.1778)
							(mid -0.249642 -0.249642)
							(end -0.1778 -0.2794)
						)
						(arc
							(start 0.1778 -0.2794)
							(mid 0.249642 -0.249642)
							(end 0.2794 -0.1778)
						)
						(arc
							(start 0.2794 0.1778)
							(mid 0.249642 0.249642)
							(end 0.1778 0.2794)
						)
					)
					(width 0)
					(fill yes)
				)
			)
		)
		(pad "2" smd custom
			(at 0 0.4445 90)
			(size 0.1397 0.1397)
			(layers "B.Cu" "B.Mask" "B.Paste")
			(net "I2C_IOC_2_SDA")
			(options
				(clearance outline)
				(anchor circle)
			)
			(primitives
				(gr_poly
					(pts
						(arc
							(start -0.1778 0.2794)
							(mid -0.249642 0.249642)
							(end -0.2794 0.1778)
						)
						(arc
							(start -0.2794 -0.1778)
							(mid -0.249642 -0.249642)
							(end -0.1778 -0.2794)
						)
						(arc
							(start 0.1778 -0.2794)
							(mid 0.249642 -0.249642)
							(end 0.2794 -0.1778)
						)
						(arc
							(start 0.2794 0.1778)
							(mid 0.249642 0.249642)
							(end 0.1778 0.2794)
						)
					)
					(width 0)
					(fill yes)
				)
			)
		)
	)
	(footprint ""
		(layer "B.Cu")
		(at 70.612 -57.023 90)
		(property "Reference" "R160"
			(at 0 0 90)
			(layer "B.SilkS")
			(hide yes)
			(effects
				(font
					(size 1.27 1.27)
				)
				(justify mirror)
			)
		)
		(property "Value" "D51R3F-2-GP"
			(at 0.0254 -2.5146 90)
			(unlocked yes)
			(layer "B.Fab")
			(hide yes)
			(effects
				(font
					(size 1.016 1.016)
					(thickness 0.1524)
				)
				(justify mirror)
			)
		)
		(property "Device Type" "R603H22"
			(at 0.0254 -4.0386 90)
			(unlocked yes)
			(layer "B.Fab")
			(hide yes)
			(effects
				(font
					(size 1.016 1.016)
					(thickness 0.1524)
				)
				(justify mirror)
			)
		)
		(duplicate_pad_numbers_are_jumpers no)
		(fp_line
			(start 0.4826 0)
			(end 0.2032 0)
			(stroke
				(width 0.2032)
				(type default)
			)
			(layer "B.SilkS")
		)
		(fp_line
			(start -0.2032 0)
			(end -0.4826 0)
			(stroke
				(width 0.2032)
				(type default)
			)
			(layer "B.SilkS")
		)
		(fp_rect
			(start 0.5842 1.3335)
			(end -0.5842 -1.3335)
			(stroke
				(width 0)
				(type default)
			)
			(fill no)
			(layer "B.CrtYd")
		)
		(fp_rect
			(start 0.5842 1.3335)
			(end -0.5842 -1.3335)
			(stroke
				(width 0)
				(type default)
			)
			(fill no)
			(layer "B.Fab")
		)
		(pad "1" smd custom
			(at 0 -0.762 270)
			(size 0.2159 0.2159)
			(layers "B.Cu" "B.Mask" "B.Paste")
			(net "P0V9")
			(options
				(clearance outline)
				(anchor circle)
			)
			(primitives
				(gr_poly
					(pts
						(arc
							(start -0.3302 0.4318)
							(mid -0.402042 0.402042)
							(end -0.4318 0.3302)
						)
						(arc
							(start -0.4318 -0.3302)
							(mid -0.402042 -0.402042)
							(end -0.3302 -0.4318)
						)
						(arc
							(start 0.3302 -0.4318)
							(mid 0.402042 -0.402042)
							(end 0.4318 -0.3302)
						)
						(arc
							(start 0.4318 0.3302)
							(mid 0.402042 0.402042)
							(end 0.3302 0.4318)
						)
					)
					(width 0)
					(fill yes)
				)
			)
		)
		(pad "2" smd custom
			(at 0 0.762 270)
			(size 0.2159 0.2159)
			(layers "B.Cu" "B.Mask" "B.Paste")
			(net "GB_VDDA")
			(options
				(clearance outline)
				(anchor circle)
			)
			(primitives
				(gr_poly
					(pts
						(arc
							(start -0.3302 0.4318)
							(mid -0.402042 0.402042)
							(end -0.4318 0.3302)
						)
						(arc
							(start -0.4318 -0.3302)
							(mid -0.402042 -0.402042)
							(end -0.3302 -0.4318)
						)
						(arc
							(start 0.3302 -0.4318)
							(mid 0.402042 -0.402042)
							(end 0.4318 -0.3302)
						)
						(arc
							(start 0.4318 0.3302)
							(mid 0.402042 0.402042)
							(end 0.3302 0.4318)
						)
					)
					(width 0)
					(fill yes)
				)
			)
		)
	)
	(footprint ""
		(layer "B.Cu")
		(at 165.608 -52.07)
		(property "Reference" "R196"
			(at 0 0 0)
			(layer "B.SilkS")
			(hide yes)
			(effects
				(font
					(size 1.27 1.27)
				)
				(justify mirror)
			)
		)
		(property "Value" "2K2R2F-GP"
			(at -0.064008 -3.993896 0)
			(unlocked yes)
			(layer "B.Fab")
			(hide yes)
			(effects
				(font
					(size 1.016 1.016)
					(thickness 0.1524)
				)
				(justify mirror)
			)
		)
		(property "Device Type" "R402H16"
			(at -0.064008 -5.517896 0)
			(unlocked yes)
			(layer "B.Fab")
			(hide yes)
			(effects
				(font
					(size 1.016 1.016)
					(thickness 0.1524)
				)
				(justify mirror)
			)
		)
		(duplicate_pad_numbers_are_jumpers no)
		(fp_line
			(start -0.508 -0.9398)
			(end 0.508 -0.9398)
			(stroke
				(width 0.1524)
				(type default)
			)
			(layer "B.SilkS")
		)
		(fp_line
			(start 0.508 -0.9398)
			(end 0.508 0.9398)
			(stroke
				(width 0.1524)
				(type default)
			)
			(layer "B.SilkS")
		)
		(fp_rect
			(start 0.508 0.9398)
			(end -0.508 -0.9398)
			(stroke
				(width 0)
				(type default)
			)
			(fill no)
			(layer "B.CrtYd")
		)
		(fp_rect
			(start 0.508 0.9398)
			(end -0.508 -0.9398)
			(stroke
				(width 0)
				(type default)
			)
			(fill no)
			(layer "B.Fab")
		)
		(pad "1" smd custom
			(at 0 -0.4445 180)
			(size 0.1397 0.1397)
			(layers "B.Cu" "B.Mask" "B.Paste")
			(net "P1V8_C")
			(options
				(clearance outline)
				(anchor circle)
			)
			(primitives
				(gr_poly
					(pts
						(arc
							(start -0.1778 0.2794)
							(mid -0.249642 0.249642)
							(end -0.2794 0.1778)
						)
						(arc
							(start -0.2794 -0.1778)
							(mid -0.249642 -0.249642)
							(end -0.1778 -0.2794)
						)
						(arc
							(start 0.1778 -0.2794)
							(mid 0.249642 -0.249642)
							(end 0.2794 -0.1778)
						)
						(arc
							(start 0.2794 0.1778)
							(mid 0.249642 0.249642)
							(end 0.1778 0.2794)
						)
					)
					(width 0)
					(fill yes)
				)
			)
		)
		(pad "2" smd custom
			(at 0 0.4445 180)
			(size 0.1397 0.1397)
			(layers "B.Cu" "B.Mask" "B.Paste")
			(net "SIO_LOAD_0")
			(options
				(clearance outline)
				(anchor circle)
			)
			(primitives
				(gr_poly
					(pts
						(arc
							(start -0.1778 0.2794)
							(mid -0.249642 0.249642)
							(end -0.2794 0.1778)
						)
						(arc
							(start -0.2794 -0.1778)
							(mid -0.249642 -0.249642)
							(end -0.1778 -0.2794)
						)
						(arc
							(start 0.1778 -0.2794)
							(mid 0.249642 -0.249642)
							(end 0.2794 -0.1778)
						)
						(arc
							(start 0.2794 0.1778)
							(mid 0.249642 0.249642)
							(end 0.1778 0.2794)
						)
					)
					(width 0)
					(fill yes)
				)
			)
		)
	)
	(footprint ""
		(layer "B.Cu")
		(at 121.9454 -92.3036 90)
		(property "Reference" "R560"
			(at 0 0 90)
			(layer "B.SilkS")
			(hide yes)
			(effects
				(font
					(size 1.27 1.27)
				)
				(justify mirror)
			)
		)
		(property "Value" "10KR2F-2-GP"
			(at -0.064008 -3.993896 90)
			(unlocked yes)
			(layer "B.Fab")
			(hide yes)
			(effects
				(font
					(size 1.016 1.016)
					(thickness 0.1524)
				)
				(justify mirror)
			)
		)
		(property "Device Type" "R402H16"
			(at -0.064008 -5.517896 90)
			(unlocked yes)
			(layer "B.Fab")
			(hide yes)
			(effects
				(font
					(size 1.016 1.016)
					(thickness 0.1524)
				)
				(justify mirror)
			)
		)
		(duplicate_pad_numbers_are_jumpers no)
		(fp_line
			(start 0.508 -0.9398)
			(end 0.508 0.9398)
			(stroke
				(width 0.1524)
				(type default)
			)
			(layer "B.SilkS")
		)
		(fp_line
			(start -0.508 -0.9398)
			(end 0.508 -0.9398)
			(stroke
				(width 0.1524)
				(type default)
			)
			(layer "B.SilkS")
		)
		(fp_rect
			(start 0.508 0.9398)
			(end -0.508 -0.9398)
			(stroke
				(width 0)
				(type default)
			)
			(fill no)
			(layer "B.CrtYd")
		)
		(fp_rect
			(start 0.508 0.9398)
			(end -0.508 -0.9398)
			(stroke
				(width 0)
				(type default)
			)
			(fill no)
			(layer "B.Fab")
		)
		(pad "1" smd custom
			(at 0 -0.4445 270)
			(size 0.1397 0.1397)
			(layers "B.Cu" "B.Mask" "B.Paste")
			(net "SCC_RMT_HEARTBEAT_LS")
			(options
				(clearance outline)
				(anchor circle)
			)
			(primitives
				(gr_poly
					(pts
						(arc
							(start -0.1778 0.2794)
							(mid -0.249642 0.249642)
							(end -0.2794 0.1778)
						)
						(arc
							(start -0.2794 -0.1778)
							(mid -0.249642 -0.249642)
							(end -0.1778 -0.2794)
						)
						(arc
							(start 0.1778 -0.2794)
							(mid 0.249642 -0.249642)
							(end 0.2794 -0.1778)
						)
						(arc
							(start 0.2794 0.1778)
							(mid 0.249642 0.249642)
							(end 0.1778 0.2794)
						)
					)
					(width 0)
					(fill yes)
				)
			)
		)
		(pad "2" smd custom
			(at 0 0.4445 270)
			(size 0.1397 0.1397)
			(layers "B.Cu" "B.Mask" "B.Paste")
			(net "P1V8_E")
			(options
				(clearance outline)
				(anchor circle)
			)
			(primitives
				(gr_poly
					(pts
						(arc
							(start -0.1778 0.2794)
							(mid -0.249642 0.249642)
							(end -0.2794 0.1778)
						)
						(arc
							(start -0.2794 -0.1778)
							(mid -0.249642 -0.249642)
							(end -0.1778 -0.2794)
						)
						(arc
							(start 0.1778 -0.2794)
							(mid 0.249642 -0.249642)
							(end 0.2794 -0.1778)
						)
						(arc
							(start 0.2794 0.1778)
							(mid 0.249642 0.249642)
							(end 0.1778 0.2794)
						)
					)
					(width 0)
					(fill yes)
				)
			)
		)
	)
	(footprint ""
		(layer "B.Cu")
		(at 167.132 -66.802 180)
		(property "Reference" "L19"
			(at 0 0 0)
			(layer "B.SilkS")
			(hide yes)
			(effects
				(font
					(size 1.27 1.27)
				)
				(justify mirror)
			)
		)
		(property "Value" "MPZ2012S601AT-GP"
			(at 0 -4.2418 180)
			(unlocked yes)
			(layer "B.Fab")
			(hide yes)
			(effects
				(font
					(size 1.016 1.016)
					(thickness 0.1524)
				)
				(justify mirror)
			)
		)
		(property "Device Type" "L805H42"
			(at 0 -5.7912 180)
			(unlocked yes)
			(layer "B.Fab")
			(hide yes)
			(effects
				(font
					(size 1.016 1.016)
					(thickness 0.1524)
				)
				(justify mirror)
			)
		)
		(duplicate_pad_numbers_are_jumpers no)
		(fp_line
			(start 0.889 1.7018)
			(end 0.889 -1.7018)
			(stroke
				(width 0.1524)
				(type default)
			)
			(layer "B.SilkS")
		)
		(fp_line
			(start 0.889 -1.7018)
			(end -0.889 -1.7018)
			(stroke
				(width 0.1524)
				(type default)
			)
			(layer "B.SilkS")
		)
		(fp_line
			(start -0.889 1.7018)
			(end 0.889 1.7018)
			(stroke
				(width 0.1524)
				(type default)
			)
			(layer "B.SilkS")
		)
		(fp_line
			(start -0.889 -1.7018)
			(end -0.889 1.7018)
			(stroke
				(width 0.1524)
				(type default)
			)
			(layer "B.SilkS")
		)
		(fp_rect
			(start 0.9652 1.778)
			(end -0.9652 -1.778)
			(stroke
				(width 0)
				(type default)
			)
			(fill no)
			(layer "B.CrtYd")
		)
		(fp_rect
			(start 0.9652 1.778)
			(end -0.9652 -1.778)
			(stroke
				(width 0)
				(type default)
			)
			(fill no)
			(layer "B.Fab")
		)
		(pad "1" smd rect
			(at 0 -0.9652)
			(size 1.397 1.143)
			(layers "B.Cu" "B.Mask" "B.Paste")
			(net "HM40ADC_VDDA")
		)
		(pad "2" smd rect
			(at 0 0.9652)
			(size 1.397 1.143)
			(layers "B.Cu" "B.Mask" "B.Paste")
			(net "P1V8_C")
		)
	)
)
